# T6G (Grand Teton) — schematic netlist excerpt (pin names and nets, part order shuffled) for the footprints in the layout excerpt that follows; sources: Cadence DE-HDL packaged netlist, KiCad conversion of 04192023_DAF0TMB3IC0_F0TG_MB_C_brd_V02_OCP.brd

PR316  Q_RES  1 1% CHIP  pkg 0402LF  page 193 : A = PVDDCR_CPU0_P0_VCC ; B = P3V3_AUX
R3088  Q_RES  130 1% CHIP  pkg 0402LF  page 255 : A = LED_PWRGD_PVDDCR_CPU1_P0_R ; B = P3V3_AUX

(kicad_pcb
	(version 20260206)
	(generator "pcbnew")
	(generator_version "10.0")
	(general
		(thickness 1.6)
		(legacy_teardrops no)
	)
	(paper "A4")
	(title_block
		(title "04192023_DAF0TMB3IC0_F0TG_MB_C_brd_V02_OCP.brd")
		(comment 1 "Grand Teton / footprints 5293-5294 of 8354")
	)
	(layers
		(0 "F.Cu" signal "TOP")
		(4 "In1.Cu" signal "GND")
		(6 "In2.Cu" signal "IN1")
		(8 "In3.Cu" signal "GND1")
		(10 "In4.Cu" signal "IN2")
		(12 "In5.Cu" signal "GND2")
		(14 "In6.Cu" signal "IN3")
		(16 "In7.Cu" signal "GND3")
		(18 "In8.Cu" signal "VCC")
		(20 "In9.Cu" signal "VCC1")
		(22 "In10.Cu" signal "GND4")
		(24 "In11.Cu" signal "IN4")
		(26 "In12.Cu" signal "GND5")
		(28 "In13.Cu" signal "IN5")
		(30 "In14.Cu" signal "GND6")
		(32 "In15.Cu" signal "IN6")
		(34 "In16.Cu" signal "GND7")
		(2 "B.Cu" signal "BOTTOM")
		(9 "F.Adhes" user "F.Adhesive")
		(11 "B.Adhes" user "B.Adhesive")
		(13 "F.Paste" user "Package Geometry/Pastemask Top")
		(15 "B.Paste" user "Package Geometry/Pastemask Bottom")
		(5 "F.SilkS" user "Ref Des/Silkscreen Top")
		(7 "B.SilkS" user "Ref Des/Silkscreen Bottom")
		(1 "F.Mask" user "Board Geometry/Soldermask Top")
		(3 "B.Mask" user "Board Geometry/Soldermask Bottom")
		(17 "Dwgs.User" user "User.Drawings")
		(19 "Cmts.User" user "User.Comments")
		(21 "Eco1.User" user "User.Eco1")
		(23 "Eco2.User" user "User.Eco2")
		(25 "Edge.Cuts" user "Board Geometry/Outline")
		(27 "Margin" user)
		(31 "F.CrtYd" user "Package Geometry/Place Bound Top")
		(29 "B.CrtYd" user "Package Geometry/Place Bound Bottom")
		(35 "F.Fab" user "Ref Des/Assembly Top")
		(33 "B.Fab" user "Ref Des/Assembly Bottom")
	)
	(footprint ""
		(layer "B.Cu")
		(at 328.699876 -66.708782 90)
		(property "Reference" "R3088"
			(at 0 0 90)
			(layer "B.SilkS")
			(hide yes)
			(effects
				(font
					(size 1.27 1.27)
				)
				(justify mirror)
			)
		)
		(property "Value" ""
			(at 0 0 90)
			(layer "B.Fab")
			(effects
				(font
					(size 1.27 1.27)
				)
				(justify mirror)
			)
		)
		(duplicate_pad_numbers_are_jumpers no)
		(fp_line
			(start 0.7874 -0.4064)
			(end -0.7874 -0.4064)
			(stroke
				(width 0.1524)
				(type default)
			)
			(layer "B.SilkS")
		)
		(fp_line
			(start -0.7874 -0.4064)
			(end -0.7874 0.4064)
			(stroke
				(width 0.1524)
				(type default)
			)
			(layer "B.SilkS")
		)
		(fp_line
			(start 0.7874 0.4064)
			(end 0.7874 -0.4064)
			(stroke
				(width 0.1524)
				(type default)
			)
			(layer "B.SilkS")
		)
		(fp_line
			(start -0.7874 0.4064)
			(end 0.7874 0.4064)
			(stroke
				(width 0.1524)
				(type default)
			)
			(layer "B.SilkS")
		)
		(fp_line
			(start 0.67945 -0.305054)
			(end 0.12065 -0.305054)
			(stroke
				(width 0.1)
				(type default)
			)
			(layer "B.Fab")
		)
		(fp_line
			(start 0.12065 -0.305054)
			(end 0.12065 -0.2794)
			(stroke
				(width 0.1)
				(type default)
			)
			(layer "B.Fab")
		)
		(fp_line
			(start -0.12065 -0.3048)
			(end -0.67945 -0.3048)
			(stroke
				(width 0.1)
				(type default)
			)
			(layer "B.Fab")
		)
		(fp_line
			(start -0.67945 -0.3048)
			(end -0.67945 0.3048)
			(stroke
				(width 0.1)
				(type default)
			)
			(layer "B.Fab")
		)
		(fp_line
			(start 0.12065 -0.2794)
			(end -0.12065 -0.2794)
			(stroke
				(width 0.1)
				(type default)
			)
			(layer "B.Fab")
		)
		(fp_line
			(start -0.12065 -0.2794)
			(end -0.12065 -0.3048)
			(stroke
				(width 0.1)
				(type default)
			)
			(layer "B.Fab")
		)
		(fp_line
			(start 0.12065 0.2794)
			(end 0.12065 0.3048)
			(stroke
				(width 0.1)
				(type default)
			)
			(layer "B.Fab")
		)
		(fp_line
			(start -0.120396 0.2794)
			(end 0.12065 0.2794)
			(stroke
				(width 0.1)
				(type default)
			)
			(layer "B.Fab")
		)
		(fp_line
			(start 0.67945 0.3048)
			(end 0.67945 -0.305054)
			(stroke
				(width 0.1)
				(type default)
			)
			(layer "B.Fab")
		)
		(fp_line
			(start 0.12065 0.3048)
			(end 0.67945 0.3048)
			(stroke
				(width 0.1)
				(type default)
			)
			(layer "B.Fab")
		)
		(fp_line
			(start -0.120396 0.3048)
			(end -0.120396 0.2794)
			(stroke
				(width 0.1)
				(type default)
			)
			(layer "B.Fab")
		)
		(fp_line
			(start -0.67945 0.3048)
			(end -0.120396 0.3048)
			(stroke
				(width 0.1)
				(type default)
			)
			(layer "B.Fab")
		)
		(pad "1" smd circle
			(at 0.40005 0 270)
			(size 0 0)
			(layers "B.Cu" "B.Mask" "B.Paste")
			(net "LED_PWRGD_PVDDCR_CPU1_P0_R")
		)
		(pad "2" smd circle
			(at -0.40005 0 270)
			(size 0 0)
			(layers "B.Cu" "B.Mask" "B.Paste")
			(net "P3V3_AUX")
		)
	)
	(footprint ""
		(layer "B.Cu")
		(at 385.256278 -137.535158 90)
		(property "Reference" "PR316"
			(at 0 0 90)
			(layer "B.SilkS")
			(hide yes)
			(effects
				(font
					(size 1.27 1.27)
				)
				(justify mirror)
			)
		)
		(property "Value" ""
			(at 0 0 90)
			(layer "B.Fab")
			(effects
				(font
					(size 1.27 1.27)
				)
				(justify mirror)
			)
		)
		(duplicate_pad_numbers_are_jumpers no)
		(fp_line
			(start 0.7874 -0.4064)
			(end -0.7874 -0.4064)
			(stroke
				(width 0.1524)
				(type default)
			)
			(layer "B.SilkS")
		)
		(fp_line
			(start -0.7874 -0.4064)
			(end -0.7874 0.4064)
			(stroke
				(width 0.1524)
				(type default)
			)
			(layer "B.SilkS")
		)
		(fp_line
			(start 0.7874 0.4064)
			(end 0.7874 -0.4064)
			(stroke
				(width 0.1524)
				(type default)
			)
			(layer "B.SilkS")
		)
		(fp_line
			(start -0.7874 0.4064)
			(end 0.7874 0.4064)
			(stroke
				(width 0.1524)
				(type default)
			)
			(layer "B.SilkS")
		)
		(fp_line
			(start 0.67945 -0.305054)
			(end 0.12065 -0.305054)
			(stroke
				(width 0.1)
				(type default)
			)
			(layer "B.Fab")
		)
		(fp_line
			(start 0.12065 -0.305054)
			(end 0.12065 -0.2794)
			(stroke
				(width 0.1)
				(type default)
			)
			(layer "B.Fab")
		)
		(fp_line
			(start -0.12065 -0.3048)
			(end -0.67945 -0.3048)
			(stroke
				(width 0.1)
				(type default)
			)
			(layer "B.Fab")
		)
		(fp_line
			(start -0.67945 -0.3048)
			(end -0.67945 0.3048)
			(stroke
				(width 0.1)
				(type default)
			)
			(layer "B.Fab")
		)
		(fp_line
			(start 0.12065 -0.2794)
			(end -0.12065 -0.2794)
			(stroke
				(width 0.1)
				(type default)
			)
			(layer "B.Fab")
		)
		(fp_line
			(start -0.12065 -0.2794)
			(end -0.12065 -0.3048)
			(stroke
				(width 0.1)
				(type default)
			)
			(layer "B.Fab")
		)
		(fp_line
			(start 0.12065 0.2794)
			(end 0.12065 0.3048)
			(stroke
				(width 0.1)
				(type default)
			)
			(layer "B.Fab")
		)
		(fp_line
			(start -0.120396 0.2794)
			(end 0.12065 0.2794)
			(stroke
				(width 0.1)
				(type default)
			)
			(layer "B.Fab")
		)
		(fp_line
			(start 0.67945 0.3048)
			(end 0.67945 -0.305054)
			(stroke
				(width 0.1)
				(type default)
			)
			(layer "B.Fab")
		)
		(fp_line
			(start 0.12065 0.3048)
			(end 0.67945 0.3048)
			(stroke
				(width 0.1)
				(type default)
			)
			(layer "B.Fab")
		)
		(fp_line
			(start -0.120396 0.3048)
			(end -0.120396 0.2794)
			(stroke
				(width 0.1)
				(type default)
			)
			(layer "B.Fab")
		)
		(fp_line
			(start -0.67945 0.3048)
			(end -0.120396 0.3048)
			(stroke
				(width 0.1)
				(type default)
			)
			(layer "B.Fab")
		)
		(pad "1" smd circle
			(at 0.40005 0 270)
			(size 0 0)
			(layers "B.Cu" "B.Mask" "B.Paste")
			(net "PVDDCR_CPU0_P0_VCC")
		)
		(pad "2" smd circle
			(at -0.40005 0 270)
			(size 0 0)
			(layers "B.Cu" "B.Mask" "B.Paste")
			(net "P3V3_AUX")
		)
	)
)
